(kicad_pcb
	(version 20260206)
	(generator "pcbnew")
	(generator_version "10.0")
	(general
		(thickness 1.6)
		(legacy_teardrops no)
	)
	(paper "A4")
	(title_block
		(title "04192023_DAF0TMB3IC0_F0TG_MB_C_brd_V02_OCP.brd")
		(comment 1 "Grand Teton / footprints 8339-8346 of 8354")
	)
	(layers
		(0 "F.Cu" signal "TOP")
		(4 "In1.Cu" signal "GND")
		(6 "In2.Cu" signal "IN1")
		(8 "In3.Cu" signal "GND1")
		(10 "In4.Cu" signal "IN2")
		(12 "In5.Cu" signal "GND2")
		(14 "In6.Cu" signal "IN3")
		(16 "In7.Cu" signal "GND3")
		(18 "In8.Cu" signal "VCC")
		(20 "In9.Cu" signal "VCC1")
		(22 "In10.Cu" signal "GND4")
		(24 "In11.Cu" signal "IN4")
		(26 "In12.Cu" signal "GND5")
		(28 "In13.Cu" signal "IN5")
		(30 "In14.Cu" signal "GND6")
		(32 "In15.Cu" signal "IN6")
		(34 "In16.Cu" signal "GND7")
		(2 "B.Cu" signal "BOTTOM")
		(9 "F.Adhes" user "F.Adhesive")
		(11 "B.Adhes" user "B.Adhesive")
		(13 "F.Paste" user "Package Geometry/Pastemask Top")
		(15 "B.Paste" user "Package Geometry/Pastemask Bottom")
		(5 "F.SilkS" user "Ref Des/Silkscreen Top")
		(7 "B.SilkS" user "Ref Des/Silkscreen Bottom")
		(1 "F.Mask" user "Board Geometry/Soldermask Top")
		(3 "B.Mask" user "Board Geometry/Soldermask Bottom")
		(17 "Dwgs.User" user "User.Drawings")
		(19 "Cmts.User" user "User.Comments")
		(21 "Eco1.User" user "User.Eco1")
		(23 "Eco2.User" user "User.Eco2")
		(25 "Edge.Cuts" user "Board Geometry/Outline")
		(27 "Margin" user)
		(31 "F.CrtYd" user "Package Geometry/Place Bound Top")
		(29 "B.CrtYd" user "Package Geometry/Place Bound Bottom")
		(35 "F.Fab" user "Ref Des/Assembly Top")
		(33 "B.Fab" user "Ref Des/Assembly Bottom")
	)
	(footprint ""
		(layer "B.Cu")
		(at 122.10669 -248.479564)
		(property "Reference" "C2315"
			(at 0 0 0)
			(layer "B.SilkS")
			(hide yes)
			(effects
				(font
					(size 1.27 1.27)
				)
				(justify mirror)
			)
		)
		(property "Value" ""
			(at 0 0 0)
			(layer "B.Fab")
			(effects
				(font
					(size 1.27 1.27)
				)
				(justify mirror)
			)
		)
		(duplicate_pad_numbers_are_jumpers no)
		(fp_line
			(start -0.7874 -0.4064)
			(end -0.7874 0.4064)
			(stroke
				(width 0.1524)
				(type default)
			)
			(layer "B.SilkS")
		)
		(fp_line
			(start -0.7874 0.4064)
			(end 0.7874 0.4064)
			(stroke
				(width 0.1524)
				(type default)
			)
			(layer "B.SilkS")
		)
		(fp_line
			(start 0.7874 -0.4064)
			(end -0.7874 -0.4064)
			(stroke
				(width 0.1524)
				(type default)
			)
			(layer "B.SilkS")
		)
		(fp_line
			(start 0.7874 0.4064)
			(end 0.7874 -0.4064)
			(stroke
				(width 0.1524)
				(type default)
			)
			(layer "B.SilkS")
		)
		(fp_line
			(start -0.67945 -0.3048)
			(end -0.67945 0.3048)
			(stroke
				(width 0.1)
				(type default)
			)
			(layer "B.Fab")
		)
		(fp_line
			(start -0.67945 0.3048)
			(end -0.120396 0.3048)
			(stroke
				(width 0.1)
				(type default)
			)
			(layer "B.Fab")
		)
		(fp_line
			(start -0.12065 -0.3048)
			(end -0.67945 -0.3048)
			(stroke
				(width 0.1)
				(type default)
			)
			(layer "B.Fab")
		)
		(fp_line
			(start -0.12065 -0.2794)
			(end -0.12065 -0.3048)
			(stroke
				(width 0.1)
				(type default)
			)
			(layer "B.Fab")
		)
		(fp_line
			(start -0.120396 0.2794)
			(end 0.12065 0.2794)
			(stroke
				(width 0.1)
				(type default)
			)
			(layer "B.Fab")
		)
		(fp_line
			(start -0.120396 0.3048)
			(end -0.120396 0.2794)
			(stroke
				(width 0.1)
				(type default)
			)
			(layer "B.Fab")
		)
		(fp_line
			(start 0.12065 -0.305054)
			(end 0.12065 -0.2794)
			(stroke
				(width 0.1)
				(type default)
			)
			(layer "B.Fab")
		)
		(fp_line
			(start 0.12065 -0.2794)
			(end -0.12065 -0.2794)
			(stroke
				(width 0.1)
				(type default)
			)
			(layer "B.Fab")
		)
		(fp_line
			(start 0.12065 0.2794)
			(end 0.12065 0.3048)
			(stroke
				(width 0.1)
				(type default)
			)
			(layer "B.Fab")
		)
		(fp_line
			(start 0.12065 0.3048)
			(end 0.67945 0.3048)
			(stroke
				(width 0.1)
				(type default)
			)
			(layer "B.Fab")
		)
		(fp_line
			(start 0.67945 -0.305054)
			(end 0.12065 -0.305054)
			(stroke
				(width 0.1)
				(type default)
			)
			(layer "B.Fab")
		)
		(fp_line
			(start 0.67945 0.3048)
			(end 0.67945 -0.305054)
			(stroke
				(width 0.1)
				(type default)
			)
			(layer "B.Fab")
		)
		(pad "1" smd circle
			(at 0.40005 0 180)
			(size 0 0)
			(layers "B.Cu" "B.Mask" "B.Paste")
			(net "PVDDCR_CPU0_P1")
		)
		(pad "2" smd circle
			(at -0.40005 0 180)
			(size 0 0)
			(layers "B.Cu" "B.Mask" "B.Paste")
			(net "GND")
		)
	)
	(footprint ""
		(layer "B.Cu")
		(at 117.895624 -259.355336)
		(property "Reference" "C2420"
			(at 0 0 0)
			(layer "B.SilkS")
			(hide yes)
			(effects
				(font
					(size 1.27 1.27)
				)
				(justify mirror)
			)
		)
		(property "Value" ""
			(at 0 0 0)
			(layer "B.Fab")
			(effects
				(font
					(size 1.27 1.27)
				)
				(justify mirror)
			)
		)
		(duplicate_pad_numbers_are_jumpers no)
		(fp_line
			(start -0.7874 -0.4064)
			(end -0.7874 0.4064)
			(stroke
				(width 0.1524)
				(type default)
			)
			(layer "B.SilkS")
		)
		(fp_line
			(start -0.7874 0.4064)
			(end 0.7874 0.4064)
			(stroke
				(width 0.1524)
				(type default)
			)
			(layer "B.SilkS")
		)
		(fp_line
			(start 0.7874 -0.4064)
			(end -0.7874 -0.4064)
			(stroke
				(width 0.1524)
				(type default)
			)
			(layer "B.SilkS")
		)
		(fp_line
			(start 0.7874 0.4064)
			(end 0.7874 -0.4064)
			(stroke
				(width 0.1524)
				(type default)
			)
			(layer "B.SilkS")
		)
		(fp_line
			(start -0.67945 -0.3048)
			(end -0.67945 0.3048)
			(stroke
				(width 0.1)
				(type default)
			)
			(layer "B.Fab")
		)
		(fp_line
			(start -0.67945 0.3048)
			(end -0.120396 0.3048)
			(stroke
				(width 0.1)
				(type default)
			)
			(layer "B.Fab")
		)
		(fp_line
			(start -0.12065 -0.3048)
			(end -0.67945 -0.3048)
			(stroke
				(width 0.1)
				(type default)
			)
			(layer "B.Fab")
		)
		(fp_line
			(start -0.12065 -0.2794)
			(end -0.12065 -0.3048)
			(stroke
				(width 0.1)
				(type default)
			)
			(layer "B.Fab")
		)
		(fp_line
			(start -0.120396 0.2794)
			(end 0.12065 0.2794)
			(stroke
				(width 0.1)
				(type default)
			)
			(layer "B.Fab")
		)
		(fp_line
			(start -0.120396 0.3048)
			(end -0.120396 0.2794)
			(stroke
				(width 0.1)
				(type default)
			)
			(layer "B.Fab")
		)
		(fp_line
			(start 0.12065 -0.305054)
			(end 0.12065 -0.2794)
			(stroke
				(width 0.1)
				(type default)
			)
			(layer "B.Fab")
		)
		(fp_line
			(start 0.12065 -0.2794)
			(end -0.12065 -0.2794)
			(stroke
				(width 0.1)
				(type default)
			)
			(layer "B.Fab")
		)
		(fp_line
			(start 0.12065 0.2794)
			(end 0.12065 0.3048)
			(stroke
				(width 0.1)
				(type default)
			)
			(layer "B.Fab")
		)
		(fp_line
			(start 0.12065 0.3048)
			(end 0.67945 0.3048)
			(stroke
				(width 0.1)
				(type default)
			)
			(layer "B.Fab")
		)
		(fp_line
			(start 0.67945 -0.305054)
			(end 0.12065 -0.305054)
			(stroke
				(width 0.1)
				(type default)
			)
			(layer "B.Fab")
		)
		(fp_line
			(start 0.67945 0.3048)
			(end 0.67945 -0.305054)
			(stroke
				(width 0.1)
				(type default)
			)
			(layer "B.Fab")
		)
		(pad "1" smd circle
			(at 0.40005 0 180)
			(size 0 0)
			(layers "B.Cu" "B.Mask" "B.Paste")
			(net "PVDDCR_SOC_P1")
		)
		(pad "2" smd circle
			(at -0.40005 0 180)
			(size 0 0)
			(layers "B.Cu" "B.Mask" "B.Paste")
			(net "GND")
		)
	)
	(footprint ""
		(layer "B.Cu")
		(at 406.698958 -328.926952 180)
		(property "Reference" "R445"
			(at 0 0 0)
			(layer "B.SilkS")
			(hide yes)
			(effects
				(font
					(size 1.27 1.27)
				)
				(justify mirror)
			)
		)
		(property "Value" ""
			(at 0 0 0)
			(layer "B.Fab")
			(effects
				(font
					(size 1.27 1.27)
				)
				(justify mirror)
			)
		)
		(duplicate_pad_numbers_are_jumpers no)
		(fp_line
			(start 0.7874 0.4064)
			(end 0.7874 -0.4064)
			(stroke
				(width 0.1524)
				(type default)
			)
			(layer "B.SilkS")
		)
		(fp_line
			(start 0.7874 -0.4064)
			(end -0.7874 -0.4064)
			(stroke
				(width 0.1524)
				(type default)
			)
			(layer "B.SilkS")
		)
		(fp_line
			(start -0.7874 0.4064)
			(end 0.7874 0.4064)
			(stroke
				(width 0.1524)
				(type default)
			)
			(layer "B.SilkS")
		)
		(fp_line
			(start -0.7874 -0.4064)
			(end -0.7874 0.4064)
			(stroke
				(width 0.1524)
				(type default)
			)
			(layer "B.SilkS")
		)
		(fp_line
			(start 0.67945 0.3048)
			(end 0.67945 -0.305054)
			(stroke
				(width 0.1)
				(type default)
			)
			(layer "B.Fab")
		)
		(fp_line
			(start 0.67945 -0.305054)
			(end 0.12065 -0.305054)
			(stroke
				(width 0.1)
				(type default)
			)
			(layer "B.Fab")
		)
		(fp_line
			(start 0.12065 0.3048)
			(end 0.67945 0.3048)
			(stroke
				(width 0.1)
				(type default)
			)
			(layer "B.Fab")
		)
		(fp_line
			(start 0.12065 0.2794)
			(end 0.12065 0.3048)
			(stroke
				(width 0.1)
				(type default)
			)
			(layer "B.Fab")
		)
		(fp_line
			(start 0.12065 -0.2794)
			(end -0.12065 -0.2794)
			(stroke
				(width 0.1)
				(type default)
			)
			(layer "B.Fab")
		)
		(fp_line
			(start 0.12065 -0.305054)
			(end 0.12065 -0.2794)
			(stroke
				(width 0.1)
				(type default)
			)
			(layer "B.Fab")
		)
		(fp_line
			(start -0.120396 0.3048)
			(end -0.120396 0.2794)
			(stroke
				(width 0.1)
				(type default)
			)
			(layer "B.Fab")
		)
		(fp_line
			(start -0.120396 0.2794)
			(end 0.12065 0.2794)
			(stroke
				(width 0.1)
				(type default)
			)
			(layer "B.Fab")
		)
		(fp_line
			(start -0.12065 -0.2794)
			(end -0.12065 -0.3048)
			(stroke
				(width 0.1)
				(type default)
			)
			(layer "B.Fab")
		)
		(fp_line
			(start -0.12065 -0.3048)
			(end -0.67945 -0.3048)
			(stroke
				(width 0.1)
				(type default)
			)
			(layer "B.Fab")
		)
		(fp_line
			(start -0.67945 0.3048)
			(end -0.120396 0.3048)
			(stroke
				(width 0.1)
				(type default)
			)
			(layer "B.Fab")
		)
		(fp_line
			(start -0.67945 -0.3048)
			(end -0.67945 0.3048)
			(stroke
				(width 0.1)
				(type default)
			)
			(layer "B.Fab")
		)
		(pad "1" smd circle
			(at 0.40005 0)
			(size 0 0)
			(layers "B.Cu" "B.Mask" "B.Paste")
			(net "IRQ_BMC_SMI_N")
		)
		(pad "2" smd circle
			(at -0.40005 0)
			(size 0 0)
			(layers "B.Cu" "B.Mask" "B.Paste")
			(net "PVDD18_S5_P0")
		)
	)
	(footprint ""
		(layer "B.Cu")
		(at 357.835454 -253.43231)
		(property "Reference" "C2540"
			(at 0 0 0)
			(layer "B.SilkS")
			(hide yes)
			(effects
				(font
					(size 1.27 1.27)
				)
				(justify mirror)
			)
		)
		(property "Value" ""
			(at 0 0 0)
			(layer "B.Fab")
			(effects
				(font
					(size 1.27 1.27)
				)
				(justify mirror)
			)
		)
		(duplicate_pad_numbers_are_jumpers no)
		(fp_line
			(start -0.7874 -0.4064)
			(end -0.7874 0.4064)
			(stroke
				(width 0.1524)
				(type default)
			)
			(layer "B.SilkS")
		)
		(fp_line
			(start -0.7874 0.4064)
			(end 0.7874 0.4064)
			(stroke
				(width 0.1524)
				(type default)
			)
			(layer "B.SilkS")
		)
		(fp_line
			(start 0.7874 -0.4064)
			(end -0.7874 -0.4064)
			(stroke
				(width 0.1524)
				(type default)
			)
			(layer "B.SilkS")
		)
		(fp_line
			(start 0.7874 0.4064)
			(end 0.7874 -0.4064)
			(stroke
				(width 0.1524)
				(type default)
			)
			(layer "B.SilkS")
		)
		(fp_line
			(start -0.67945 -0.3048)
			(end -0.67945 0.3048)
			(stroke
				(width 0.1)
				(type default)
			)
			(layer "B.Fab")
		)
		(fp_line
			(start -0.67945 0.3048)
			(end -0.120396 0.3048)
			(stroke
				(width 0.1)
				(type default)
			)
			(layer "B.Fab")
		)
		(fp_line
			(start -0.12065 -0.3048)
			(end -0.67945 -0.3048)
			(stroke
				(width 0.1)
				(type default)
			)
			(layer "B.Fab")
		)
		(fp_line
			(start -0.12065 -0.2794)
			(end -0.12065 -0.3048)
			(stroke
				(width 0.1)
				(type default)
			)
			(layer "B.Fab")
		)
		(fp_line
			(start -0.120396 0.2794)
			(end 0.12065 0.2794)
			(stroke
				(width 0.1)
				(type default)
			)
			(layer "B.Fab")
		)
		(fp_line
			(start -0.120396 0.3048)
			(end -0.120396 0.2794)
			(stroke
				(width 0.1)
				(type default)
			)
			(layer "B.Fab")
		)
		(fp_line
			(start 0.12065 -0.305054)
			(end 0.12065 -0.2794)
			(stroke
				(width 0.1)
				(type default)
			)
			(layer "B.Fab")
		)
		(fp_line
			(start 0.12065 -0.2794)
			(end -0.12065 -0.2794)
			(stroke
				(width 0.1)
				(type default)
			)
			(layer "B.Fab")
		)
		(fp_line
			(start 0.12065 0.2794)
			(end 0.12065 0.3048)
			(stroke
				(width 0.1)
				(type default)
			)
			(layer "B.Fab")
		)
		(fp_line
			(start 0.12065 0.3048)
			(end 0.67945 0.3048)
			(stroke
				(width 0.1)
				(type default)
			)
			(layer "B.Fab")
		)
		(fp_line
			(start 0.67945 -0.305054)
			(end 0.12065 -0.305054)
			(stroke
				(width 0.1)
				(type default)
			)
			(layer "B.Fab")
		)
		(fp_line
			(start 0.67945 0.3048)
			(end 0.67945 -0.305054)
			(stroke
				(width 0.1)
				(type default)
			)
			(layer "B.Fab")
		)
		(pad "1" smd circle
			(at 0.40005 0 180)
			(size 0 0)
			(layers "B.Cu" "B.Mask" "B.Paste")
			(net "PVDDCR_SOC_P0")
		)
		(pad "2" smd circle
			(at -0.40005 0 180)
			(size 0 0)
			(layers "B.Cu" "B.Mask" "B.Paste")
			(net "GND")
		)
	)
	(footprint ""
		(layer "B.Cu")
		(at 187.111894 -115.022376 180)
		(property "Reference" "C1171"
			(at 0 0 0)
			(layer "B.SilkS")
			(hide yes)
			(effects
				(font
					(size 1.27 1.27)
				)
				(justify mirror)
			)
		)
		(property "Value" ""
			(at 0 0 0)
			(layer "B.Fab")
			(effects
				(font
					(size 1.27 1.27)
				)
				(justify mirror)
			)
		)
		(duplicate_pad_numbers_are_jumpers no)
		(fp_line
			(start 0.69215 0.2921)
			(end 0.69215 -0.2921)
			(stroke
				(width 0.1524)
				(type default)
			)
			(layer "B.SilkS")
		)
		(fp_line
			(start 0.69215 -0.2921)
			(end -0.69215 -0.2921)
			(stroke
				(width 0.1524)
				(type default)
			)
			(layer "B.SilkS")
		)
		(fp_line
			(start -0.69215 0.2921)
			(end 0.69215 0.2921)
			(stroke
				(width 0.1524)
				(type default)
			)
			(layer "B.SilkS")
		)
		(fp_line
			(start -0.69215 -0.2921)
			(end -0.69215 0.2921)
			(stroke
				(width 0.1524)
				(type default)
			)
			(layer "B.SilkS")
		)
		(fp_line
			(start 0.51435 0.2794)
			(end 0.51435 -0.2794)
			(stroke
				(width 0.1)
				(type default)
			)
			(layer "B.Fab")
		)
		(fp_line
			(start 0.51435 -0.2794)
			(end -0.51435 -0.2794)
			(stroke
				(width 0.1)
				(type default)
			)
			(layer "B.Fab")
		)
		(fp_line
			(start -0.51435 0.2794)
			(end 0.51435 0.2794)
			(stroke
				(width 0.1)
				(type default)
			)
			(layer "B.Fab")
		)
		(fp_line
			(start -0.51435 -0.2794)
			(end -0.51435 0.2794)
			(stroke
				(width 0.1)
				(type default)
			)
			(layer "B.Fab")
		)
		(pad "1" smd circle
			(at 0.40005 0)
			(size 0 0)
			(layers "B.Cu" "B.Mask" "B.Paste")
			(net "P3V3_AUX")
		)
		(pad "2" smd circle
			(at -0.40005 0)
			(size 0 0)
			(layers "B.Cu" "B.Mask" "B.Paste")
			(net "GND")
		)
		(zone
			(layer "B.Cu")
			(hatch none 0.5)
			(connect_pads
				(clearance 0)
			)
			(min_thickness 0.25)
			(keepout
				(tracks not_allowed)
				(vias allowed)
				(pads allowed)
				(copperpour not_allowed)
				(footprints allowed)
			)
			(placement
				(enabled no)
				(sheetname "")
			)
			(fill
				(thermal_gap 0.5)
				(thermal_bridge_width 0.5)
				(island_removal_mode 0)
			)
			(polygon
				(pts
					(xy 186.921394 -114.934492) (xy 186.921394 -115.110006) (xy 187.012834 -115.168172) (xy 187.212224 -115.168172)
					(xy 187.302394 -115.110006) (xy 187.302394 -114.934746) (xy 187.212224 -114.876326) (xy 187.012834 -114.876326)
				)
			)
		)
	)
	(footprint ""
		(layer "B.Cu")
		(at 416.468052 -192.660016)
		(property "Reference" "C158"
			(at 0 0 0)
			(layer "B.SilkS")
			(hide yes)
			(effects
				(font
					(size 1.27 1.27)
				)
				(justify mirror)
			)
		)
		(property "Value" ""
			(at 0 0 0)
			(layer "B.Fab")
			(effects
				(font
					(size 1.27 1.27)
				)
				(justify mirror)
			)
		)
		(duplicate_pad_numbers_are_jumpers no)
		(fp_line
			(start -1.524 -0.762)
			(end -1.524 0.762)
			(stroke
				(width 0.1524)
				(type default)
			)
			(layer "B.SilkS")
		)
		(fp_line
			(start -1.524 0.762)
			(end 1.524 0.762)
			(stroke
				(width 0.1524)
				(type default)
			)
			(layer "B.SilkS")
		)
		(fp_line
			(start 1.524 -0.762)
			(end -1.524 -0.762)
			(stroke
				(width 0.1524)
				(type default)
			)
			(layer "B.SilkS")
		)
		(fp_line
			(start 1.524 0.762)
			(end 1.524 -0.762)
			(stroke
				(width 0.1524)
				(type default)
			)
			(layer "B.SilkS")
		)
		(fp_line
			(start -1.1049 -0.724916)
			(end 1.1049 -0.724916)
			(stroke
				(width 0.1)
				(type default)
			)
			(layer "B.Fab")
		)
		(fp_line
			(start -1.1049 0.724916)
			(end -1.1049 -0.724916)
			(stroke
				(width 0.1)
				(type default)
			)
			(layer "B.Fab")
		)
		(fp_line
			(start 1.1049 -0.724916)
			(end 1.1049 0.724916)
			(stroke
				(width 0.1)
				(type default)
			)
			(layer "B.Fab")
		)
		(fp_line
			(start 1.1049 0.724916)
			(end -1.1049 0.724916)
			(stroke
				(width 0.1)
				(type default)
			)
			(layer "B.Fab")
		)
		(pad "1" smd rect
			(at 0.889 0)
			(size 1.016 1.27)
			(layers "B.Cu" "B.Mask" "B.Paste")
			(net "P12V_MEM_CPU0")
		)
		(pad "2" smd rect
			(at -0.889 0)
			(size 1.016 1.27)
			(layers "B.Cu" "B.Mask" "B.Paste")
			(net "GND")
		)
	)
	(footprint ""
		(layer "B.Cu")
		(at 55.918608 -388.011162 -90)
		(property "Reference" "C126"
			(at 0 0 90)
			(layer "B.SilkS")
			(hide yes)
			(effects
				(font
					(size 1.27 1.27)
				)
				(justify mirror)
			)
		)
		(property "Value" ""
			(at 0 0 90)
			(layer "B.Fab")
			(effects
				(font
					(size 1.27 1.27)
				)
				(justify mirror)
			)
		)
		(duplicate_pad_numbers_are_jumpers no)
		(fp_line
			(start -0.299974 0.150114)
			(end 0.299974 0.150114)
			(stroke
				(width 0.1)
				(type default)
			)
			(layer "B.Fab")
		)
		(fp_line
			(start 0.299974 0.150114)
			(end 0.299974 -0.150114)
			(stroke
				(width 0.1)
				(type default)
			)
			(layer "B.Fab")
		)
		(fp_line
			(start -0.299974 -0.150114)
			(end -0.299974 0.150114)
			(stroke
				(width 0.1)
				(type default)
			)
			(layer "B.Fab")
		)
		(fp_line
			(start 0.299974 -0.150114)
			(end -0.299974 -0.150114)
			(stroke
				(width 0.1)
				(type default)
			)
			(layer "B.Fab")
		)
		(pad "1" smd rect
			(at 0.2667 0 90)
			(size 0.3048 0.381)
			(layers "B.Cu" "B.Mask" "B.Paste")
			(net "P1V8_CPU1_RT0_1A")
		)
		(pad "2" smd rect
			(at -0.2667 0 90)
			(size 0.3048 0.381)
			(layers "B.Cu" "B.Mask" "B.Paste")
			(net "GND")
		)
	)
	(footprint ""
		(layer "B.Cu")
		(at 43.265852 -385.91236 180)
		(property "Reference" "R719"
			(at 0 0 0)
			(layer "B.SilkS")
			(hide yes)
			(effects
				(font
					(size 1.27 1.27)
				)
				(justify mirror)
			)
		)
		(property "Value" ""
			(at 0 0 0)
			(layer "B.Fab")
			(effects
				(font
					(size 1.27 1.27)
				)
				(justify mirror)
			)
		)
		(duplicate_pad_numbers_are_jumpers no)
		(fp_line
			(start 0.32512 0.175006)
			(end 0.32512 -0.175006)
			(stroke
				(width 0.1)
				(type default)
			)
			(layer "B.Fab")
		)
		(fp_line
			(start 0.32512 -0.175006)
			(end -0.32512 -0.175006)
			(stroke
				(width 0.1)
				(type default)
			)
			(layer "B.Fab")
		)
		(fp_line
			(start -0.32512 0.175006)
			(end 0.32512 0.175006)
			(stroke
				(width 0.1)
				(type default)
			)
			(layer "B.Fab")
		)
		(fp_line
			(start -0.32512 -0.175006)
			(end -0.32512 0.175006)
			(stroke
				(width 0.1)
				(type default)
			)
			(layer "B.Fab")
		)
		(pad "1" smd rect
			(at 0.2667 0)
			(size 0.3048 0.381)
			(layers "B.Cu" "B.Mask" "B.Paste")
			(net "TEST0_RT_CPU1_P0")
		)
		(pad "2" smd rect
			(at -0.2667 0 180)
			(size 0.3048 0.381)
			(layers "B.Cu" "B.Mask" "B.Paste")
			(net "GND")
		)
	)
)
